(kicad_pcb
	(version 20260206)
	(generator "pcbnew")
	(generator_version "10.0")
	(general
		(thickness 1.6)
		(legacy_teardrops no)
	)
	(paper "A4")
	(title_block
		(title "03242023_DA0F0TMBIJ0_F0T_Motherboard_J_brd_V01_OCP.brd")
		(comment 1 "Grand Teton / footprints 3060-3065 of 6105")
	)
	(layers
		(0 "F.Cu" signal "TOP")
		(4 "In1.Cu" signal "GND")
		(6 "In2.Cu" signal "IN1")
		(8 "In3.Cu" signal "GND1")
		(10 "In4.Cu" signal "IN2")
		(12 "In5.Cu" signal "GND2")
		(14 "In6.Cu" signal "IN3")
		(16 "In7.Cu" signal "GND3")
		(18 "In8.Cu" signal "VCC")
		(20 "In9.Cu" signal "VCC1")
		(22 "In10.Cu" signal "GND4")
		(24 "In11.Cu" signal "IN4")
		(26 "In12.Cu" signal "GND5")
		(28 "In13.Cu" signal "IN5")
		(30 "In14.Cu" signal "GND6")
		(32 "In15.Cu" signal "IN6")
		(34 "In16.Cu" signal "GND7")
		(2 "B.Cu" signal "BOTTOM")
		(9 "F.Adhes" user "F.Adhesive")
		(11 "B.Adhes" user "B.Adhesive")
		(13 "F.Paste" user "Package Geometry/Pastemask Top")
		(15 "B.Paste" user "Package Geometry/Pastemask Bottom")
		(5 "F.SilkS" user "Ref Des/Silkscreen Top")
		(7 "B.SilkS" user "Ref Des/Silkscreen Bottom")
		(1 "F.Mask" user "Board Geometry/Soldermask Top")
		(3 "B.Mask" user "Board Geometry/Soldermask Bottom")
		(17 "Dwgs.User" user "User.Drawings")
		(19 "Cmts.User" user "User.Comments")
		(21 "Eco1.User" user "User.Eco1")
		(23 "Eco2.User" user "User.Eco2")
		(25 "Edge.Cuts" user "Board Geometry/Outline")
		(27 "Margin" user)
		(31 "F.CrtYd" user "Package Geometry/Place Bound Top")
		(29 "B.CrtYd" user "Package Geometry/Place Bound Bottom")
		(35 "F.Fab" user "Ref Des/Assembly Top")
		(33 "B.Fab" user "Ref Des/Assembly Bottom")
	)
	(footprint ""
		(layer "F.Cu")
		(at 74.395076 -79.078836)
		(property "Reference" "D81"
			(at -38.71341 34.331402 90)
			(unlocked yes)
			(layer "F.SilkS")
			(effects
				(font
					(size 0.635 0.4064)
					(thickness 0.1524)
				)
				(justify left)
			)
		)
		(property "Value" ""
			(at 0 0 0)
			(layer "F.Fab")
			(effects
				(font
					(size 1.27 1.27)
				)
			)
		)
		(duplicate_pad_numbers_are_jumpers no)
		(fp_line
			(start -0.90678 0.4826)
			(end -0.90678 -0.4699)
			(stroke
				(width 0.1524)
				(type default)
			)
			(layer "F.SilkS")
		)
		(fp_line
			(start -0.89408 -0.4826)
			(end 0.90678 -0.4826)
			(stroke
				(width 0.1524)
				(type default)
			)
			(layer "F.SilkS")
		)
		(fp_line
			(start -0.79248 -0.4826)
			(end 1.03378 -0.4826)
			(stroke
				(width 0.1524)
				(type default)
			)
			(layer "F.SilkS")
		)
		(fp_line
			(start -0.64008 -0.4826)
			(end 1.16078 -0.4826)
			(stroke
				(width 0.1524)
				(type default)
			)
			(layer "F.SilkS")
		)
		(fp_line
			(start 0.90678 -0.4826)
			(end 0.90678 0.4826)
			(stroke
				(width 0.1524)
				(type default)
			)
			(layer "F.SilkS")
		)
		(fp_line
			(start 0.90678 0.4826)
			(end -0.90678 0.4826)
			(stroke
				(width 0.1524)
				(type default)
			)
			(layer "F.SilkS")
		)
		(fp_line
			(start 1.03378 -0.4826)
			(end 1.03378 0.4826)
			(stroke
				(width 0.1524)
				(type default)
			)
			(layer "F.SilkS")
		)
		(fp_line
			(start 1.03378 0.4826)
			(end -0.79248 0.4826)
			(stroke
				(width 0.1524)
				(type default)
			)
			(layer "F.SilkS")
		)
		(fp_line
			(start 1.16078 -0.4826)
			(end 1.16078 0.4826)
			(stroke
				(width 0.1524)
				(type default)
			)
			(layer "F.SilkS")
		)
		(fp_line
			(start 1.16078 0.4826)
			(end -0.64008 0.4826)
			(stroke
				(width 0.1524)
				(type default)
			)
			(layer "F.SilkS")
		)
		(fp_line
			(start -0.499872 -0.249936)
			(end 0.499872 -0.249936)
			(stroke
				(width 0.1)
				(type default)
			)
			(layer "F.Fab")
		)
		(fp_line
			(start -0.499872 0.249936)
			(end -0.499872 -0.249936)
			(stroke
				(width 0.1)
				(type default)
			)
			(layer "F.Fab")
		)
		(fp_line
			(start 0.499872 -0.249936)
			(end 0.499872 0.249936)
			(stroke
				(width 0.1)
				(type default)
			)
			(layer "F.Fab")
		)
		(fp_line
			(start 0.499872 0.249936)
			(end -0.499872 0.249936)
			(stroke
				(width 0.1)
				(type default)
			)
			(layer "F.Fab")
		)
		(pad "A" smd rect
			(at -0.47498 0)
			(size 0.6096 0.7112)
			(layers "F.Cu" "F.Mask" "F.Paste")
			(net "LED_PWRGD_PVPP_HBM_CPU1")
		)
		(pad "C" smd rect
			(at 0.47498 0)
			(size 0.6096 0.7112)
			(layers "F.Cu" "F.Mask" "F.Paste")
			(net "LED_PWRGD_PVPP_HBM_CPU1_D")
		)
	)
	(footprint ""
		(layer "F.Cu")
		(at 27.0383 -130.396996 180)
		(property "Reference" "PC475"
			(at 0 0 180)
			(layer "F.SilkS")
			(hide yes)
			(effects
				(font
					(size 1.27 1.27)
				)
			)
		)
		(property "Value" ""
			(at 0 0 180)
			(layer "F.Fab")
			(effects
				(font
					(size 1.27 1.27)
				)
			)
		)
		(duplicate_pad_numbers_are_jumpers no)
		(fp_line
			(start 0.7874 0.4064)
			(end -0.7874 0.4064)
			(stroke
				(width 0.1524)
				(type default)
			)
			(layer "F.SilkS")
		)
		(fp_line
			(start 0.7874 -0.4064)
			(end 0.7874 0.4064)
			(stroke
				(width 0.1524)
				(type default)
			)
			(layer "F.SilkS")
		)
		(fp_line
			(start -0.7874 0.4064)
			(end -0.7874 -0.4064)
			(stroke
				(width 0.1524)
				(type default)
			)
			(layer "F.SilkS")
		)
		(fp_line
			(start -0.7874 -0.4064)
			(end 0.7874 -0.4064)
			(stroke
				(width 0.1524)
				(type default)
			)
			(layer "F.SilkS")
		)
		(fp_line
			(start 0.67945 0.3048)
			(end 0.120396 0.3048)
			(stroke
				(width 0.1)
				(type default)
			)
			(layer "F.Fab")
		)
		(fp_line
			(start 0.67945 -0.3048)
			(end 0.67945 0.3048)
			(stroke
				(width 0.1)
				(type default)
			)
			(layer "F.Fab")
		)
		(fp_line
			(start 0.12065 -0.2794)
			(end 0.12065 -0.3048)
			(stroke
				(width 0.1)
				(type default)
			)
			(layer "F.Fab")
		)
		(fp_line
			(start 0.12065 -0.3048)
			(end 0.67945 -0.3048)
			(stroke
				(width 0.1)
				(type default)
			)
			(layer "F.Fab")
		)
		(fp_line
			(start 0.120396 0.3048)
			(end 0.120396 0.2794)
			(stroke
				(width 0.1)
				(type default)
			)
			(layer "F.Fab")
		)
		(fp_line
			(start 0.120396 0.2794)
			(end -0.12065 0.2794)
			(stroke
				(width 0.1)
				(type default)
			)
			(layer "F.Fab")
		)
		(fp_line
			(start -0.12065 0.3048)
			(end -0.67945 0.3048)
			(stroke
				(width 0.1)
				(type default)
			)
			(layer "F.Fab")
		)
		(fp_line
			(start -0.12065 0.2794)
			(end -0.12065 0.3048)
			(stroke
				(width 0.1)
				(type default)
			)
			(layer "F.Fab")
		)
		(fp_line
			(start -0.12065 -0.2794)
			(end 0.12065 -0.2794)
			(stroke
				(width 0.1)
				(type default)
			)
			(layer "F.Fab")
		)
		(fp_line
			(start -0.12065 -0.305054)
			(end -0.12065 -0.2794)
			(stroke
				(width 0.1)
				(type default)
			)
			(layer "F.Fab")
		)
		(fp_line
			(start -0.67945 0.3048)
			(end -0.67945 -0.305054)
			(stroke
				(width 0.1)
				(type default)
			)
			(layer "F.Fab")
		)
		(fp_line
			(start -0.67945 -0.305054)
			(end -0.12065 -0.305054)
			(stroke
				(width 0.1)
				(type default)
			)
			(layer "F.Fab")
		)
		(pad "1" smd circle
			(at -0.40005 0 180)
			(size 0 0)
			(layers "F.Cu" "F.Mask" "F.Paste")
			(net "PVCCINFAON_CPU1_ATSEN")
		)
		(pad "2" smd circle
			(at 0.40005 0 180)
			(size 0 0)
			(layers "F.Cu" "F.Mask" "F.Paste")
			(net "GND")
		)
	)
	(footprint ""
		(layer "F.Cu")
		(at 140.39088 -42.255948 90)
		(property "Reference" "C2007"
			(at 0 0 90)
			(layer "F.SilkS")
			(hide yes)
			(effects
				(font
					(size 1.27 1.27)
				)
			)
		)
		(property "Value" ""
			(at 0 0 90)
			(layer "F.Fab")
			(effects
				(font
					(size 1.27 1.27)
				)
			)
		)
		(duplicate_pad_numbers_are_jumpers no)
		(fp_line
			(start 0.7874 -0.4064)
			(end 0.7874 0.4064)
			(stroke
				(width 0.1524)
				(type default)
			)
			(layer "F.SilkS")
		)
		(fp_line
			(start -0.7874 -0.4064)
			(end 0.7874 -0.4064)
			(stroke
				(width 0.1524)
				(type default)
			)
			(layer "F.SilkS")
		)
		(fp_line
			(start 0.7874 0.4064)
			(end -0.7874 0.4064)
			(stroke
				(width 0.1524)
				(type default)
			)
			(layer "F.SilkS")
		)
		(fp_line
			(start -0.7874 0.4064)
			(end -0.7874 -0.4064)
			(stroke
				(width 0.1524)
				(type default)
			)
			(layer "F.SilkS")
		)
		(fp_line
			(start -0.12065 -0.305054)
			(end -0.12065 -0.2794)
			(stroke
				(width 0.1)
				(type default)
			)
			(layer "F.Fab")
		)
		(fp_line
			(start -0.67945 -0.305054)
			(end -0.12065 -0.305054)
			(stroke
				(width 0.1)
				(type default)
			)
			(layer "F.Fab")
		)
		(fp_line
			(start 0.67945 -0.3048)
			(end 0.67945 0.3048)
			(stroke
				(width 0.1)
				(type default)
			)
			(layer "F.Fab")
		)
		(fp_line
			(start 0.12065 -0.3048)
			(end 0.67945 -0.3048)
			(stroke
				(width 0.1)
				(type default)
			)
			(layer "F.Fab")
		)
		(fp_line
			(start 0.12065 -0.2794)
			(end 0.12065 -0.3048)
			(stroke
				(width 0.1)
				(type default)
			)
			(layer "F.Fab")
		)
		(fp_line
			(start -0.12065 -0.2794)
			(end 0.12065 -0.2794)
			(stroke
				(width 0.1)
				(type default)
			)
			(layer "F.Fab")
		)
		(fp_line
			(start 0.120396 0.2794)
			(end -0.12065 0.2794)
			(stroke
				(width 0.1)
				(type default)
			)
			(layer "F.Fab")
		)
		(fp_line
			(start -0.12065 0.2794)
			(end -0.12065 0.3048)
			(stroke
				(width 0.1)
				(type default)
			)
			(layer "F.Fab")
		)
		(fp_line
			(start 0.67945 0.3048)
			(end 0.120396 0.3048)
			(stroke
				(width 0.1)
				(type default)
			)
			(layer "F.Fab")
		)
		(fp_line
			(start 0.120396 0.3048)
			(end 0.120396 0.2794)
			(stroke
				(width 0.1)
				(type default)
			)
			(layer "F.Fab")
		)
		(fp_line
			(start -0.12065 0.3048)
			(end -0.67945 0.3048)
			(stroke
				(width 0.1)
				(type default)
			)
			(layer "F.Fab")
		)
		(fp_line
			(start -0.67945 0.3048)
			(end -0.67945 -0.305054)
			(stroke
				(width 0.1)
				(type default)
			)
			(layer "F.Fab")
		)
		(pad "1" smd circle
			(at -0.40005 0 90)
			(size 0 0)
			(layers "F.Cu" "F.Mask" "F.Paste")
			(net "P3V3_AUX")
		)
		(pad "2" smd circle
			(at 0.40005 0 90)
			(size 0 0)
			(layers "F.Cu" "F.Mask" "F.Paste")
			(net "GND")
		)
	)
	(footprint ""
		(layer "F.Cu")
		(at 525.408906 -303.624488 90)
		(property "Reference" "X1"
			(at -2.594864 3.123184 90)
			(unlocked yes)
			(layer "F.SilkS")
			(effects
				(font
					(size 0.7874 0.5842)
					(thickness 0.1524)
				)
				(justify left)
			)
		)
		(property "Value" ""
			(at 0 0 90)
			(layer "F.Fab")
			(effects
				(font
					(size 1.27 1.27)
				)
			)
		)
		(property "Device Type" "TP_TDR_4P_FTS_TH-TP_TDR_4P_DIPA"
			(at 1.30175 1.27 180)
			(unlocked yes)
			(layer "F.Fab")
			(hide yes)
			(effects
				(font
					(size 0.635 0.4064)
					(thickness 0.1524)
				)
			)
		)
		(property "User Part Number" "N_A"
			(at 1.30175 1.27 180)
			(unlocked yes)
			(layer "Cmts.User")
			(hide yes)
			(effects
				(font
					(size 0.635 0.4064)
					(thickness 0.1524)
				)
			)
		)
		(duplicate_pad_numbers_are_jumpers no)
		(fp_line
			(start 2.54 -1.27)
			(end 0 -1.27)
			(stroke
				(width 0.1524)
				(type default)
			)
			(layer "F.SilkS")
		)
		(fp_line
			(start 0 -1.27)
			(end 0 -0.635)
			(stroke
				(width 0.1524)
				(type default)
			)
			(layer "F.SilkS")
		)
		(fp_line
			(start 2.54 -1.1303)
			(end 2.54 -1.27)
			(stroke
				(width 0.1524)
				(type default)
			)
			(layer "F.SilkS")
		)
		(fp_line
			(start 0 0.635)
			(end 0 1.905)
			(stroke
				(width 0.1524)
				(type default)
			)
			(layer "F.SilkS")
		)
		(fp_line
			(start 2.54 1.4097)
			(end 2.54 1.1303)
			(stroke
				(width 0.1524)
				(type default)
			)
			(layer "F.SilkS")
		)
		(fp_line
			(start 0 3.175)
			(end 0 3.81)
			(stroke
				(width 0.1524)
				(type default)
			)
			(layer "F.SilkS")
		)
		(fp_line
			(start 2.54 3.81)
			(end 2.54 3.6703)
			(stroke
				(width 0.1524)
				(type default)
			)
			(layer "F.SilkS")
		)
		(fp_line
			(start 0 3.81)
			(end 2.54 3.81)
			(stroke
				(width 0.1524)
				(type default)
			)
			(layer "F.SilkS")
		)
		(fp_poly
			(pts
				(xy -0.761746 0) (xy -2.285746 0.762) (xy -2.285746 -0.762)
			)
			(stroke
				(width 0)
				(type default)
			)
			(fill yes)
			(layer "F.SilkS")
		)
		(fp_line
			(start 2.54 -1.27)
			(end 0 -1.27)
			(stroke
				(width 0.1)
				(type default)
			)
			(layer "F.Fab")
		)
		(fp_line
			(start 0 -1.27)
			(end 0 3.81)
			(stroke
				(width 0.1)
				(type default)
			)
			(layer "F.Fab")
		)
		(fp_line
			(start 2.54 3.81)
			(end 2.54 -1.27)
			(stroke
				(width 0.1)
				(type default)
			)
			(layer "F.Fab")
		)
		(fp_line
			(start 0 3.81)
			(end 2.54 3.81)
			(stroke
				(width 0.1)
				(type default)
			)
			(layer "F.Fab")
		)
		(fp_poly
			(pts
				(xy -0.761746 0) (xy -2.285746 -0.762) (xy -2.285746 0.762)
			)
			(stroke
				(width 0)
				(type default)
			)
			(fill yes)
			(layer "F.Fab")
		)
		(pad "1" thru_hole circle
			(at 0 0 90)
			(size 1.0033 1.0033)
			(drill 0.249936)
			(layers "*.Cu" "*.Mask")
			(remove_unused_layers no)
			(net "TDR_DIFF_85_TOP_DP")
			(clearance 0.10795)
			(thermal_gap 0.10795)
			(padstack
				(mode front_inner_back)
				(layer "Inner"
					(shape circle)
					(size 0.8001 0.8001)
					(clearance 0.1524)
				)
				(layer "B.Cu"
					(shape circle)
					(size 1.0033 1.0033)
					(clearance 0.10795)
				)
			)
		)
		(pad "2" thru_hole circle
			(at 2.54 0 90)
			(size 1.9939 1.9939)
			(drill 0.249936)
			(layers "*.Cu" "*.Mask")
			(remove_unused_layers no)
			(net "T1_GND")
			(clearance 0.10795)
			(thermal_gap 0.10795)
			(padstack
				(mode front_inner_back)
				(layer "Inner"
					(shape circle)
					(size 0.8001 0.8001)
					(clearance 0.1524)
				)
				(layer "B.Cu"
					(shape circle)
					(size 1.9939 1.9939)
					(clearance 0.10795)
				)
			)
		)
		(pad "3" thru_hole circle
			(at 2.54 2.54 90)
			(size 1.9939 1.9939)
			(drill 0.249936)
			(layers "*.Cu" "*.Mask")
			(remove_unused_layers no)
			(net "T1_GND")
			(clearance 0.10795)
			(thermal_gap 0.10795)
			(padstack
				(mode front_inner_back)
				(layer "Inner"
					(shape circle)
					(size 0.8001 0.8001)
					(clearance 0.1524)
				)
				(layer "B.Cu"
					(shape circle)
					(size 1.9939 1.9939)
					(clearance 0.10795)
				)
			)
		)
		(pad "4" thru_hole circle
			(at 0 2.54 90)
			(size 1.0033 1.0033)
			(drill 0.249936)
			(layers "*.Cu" "*.Mask")
			(remove_unused_layers no)
			(net "TDR_DIFF_85_TOP_DN")
			(clearance 0.10795)
			(thermal_gap 0.10795)
			(padstack
				(mode front_inner_back)
				(layer "Inner"
					(shape circle)
					(size 0.8001 0.8001)
					(clearance 0.1524)
				)
				(layer "B.Cu"
					(shape circle)
					(size 1.0033 1.0033)
					(clearance 0.10795)
				)
			)
		)
	)
	(footprint ""
		(layer "F.Cu")
		(at 193.38036 -122.900948)
		(property "Reference" "R2792"
			(at 0 0 0)
			(layer "F.SilkS")
			(hide yes)
			(effects
				(font
					(size 1.27 1.27)
				)
			)
		)
		(property "Value" ""
			(at 0 0 0)
			(layer "F.Fab")
			(effects
				(font
					(size 1.27 1.27)
				)
			)
		)
		(duplicate_pad_numbers_are_jumpers no)
		(fp_line
			(start -0.7874 -0.4064)
			(end 0.7874 -0.4064)
			(stroke
				(width 0.1524)
				(type default)
			)
			(layer "F.SilkS")
		)
		(fp_line
			(start -0.7874 0.4064)
			(end -0.7874 -0.4064)
			(stroke
				(width 0.1524)
				(type default)
			)
			(layer "F.SilkS")
		)
		(fp_line
			(start 0.7874 -0.4064)
			(end 0.7874 0.4064)
			(stroke
				(width 0.1524)
				(type default)
			)
			(layer "F.SilkS")
		)
		(fp_line
			(start 0.7874 0.4064)
			(end -0.7874 0.4064)
			(stroke
				(width 0.1524)
				(type default)
			)
			(layer "F.SilkS")
		)
		(fp_line
			(start -0.67945 -0.305054)
			(end -0.12065 -0.305054)
			(stroke
				(width 0.1)
				(type default)
			)
			(layer "F.Fab")
		)
		(fp_line
			(start -0.67945 0.3048)
			(end -0.67945 -0.305054)
			(stroke
				(width 0.1)
				(type default)
			)
			(layer "F.Fab")
		)
		(fp_line
			(start -0.12065 -0.305054)
			(end -0.12065 -0.2794)
			(stroke
				(width 0.1)
				(type default)
			)
			(layer "F.Fab")
		)
		(fp_line
			(start -0.12065 -0.2794)
			(end 0.12065 -0.2794)
			(stroke
				(width 0.1)
				(type default)
			)
			(layer "F.Fab")
		)
		(fp_line
			(start -0.12065 0.2794)
			(end -0.12065 0.3048)
			(stroke
				(width 0.1)
				(type default)
			)
			(layer "F.Fab")
		)
		(fp_line
			(start -0.12065 0.3048)
			(end -0.67945 0.3048)
			(stroke
				(width 0.1)
				(type default)
			)
			(layer "F.Fab")
		)
		(fp_line
			(start 0.120396 0.2794)
			(end -0.12065 0.2794)
			(stroke
				(width 0.1)
				(type default)
			)
			(layer "F.Fab")
		)
		(fp_line
			(start 0.120396 0.3048)
			(end 0.120396 0.2794)
			(stroke
				(width 0.1)
				(type default)
			)
			(layer "F.Fab")
		)
		(fp_line
			(start 0.12065 -0.3048)
			(end 0.67945 -0.3048)
			(stroke
				(width 0.1)
				(type default)
			)
			(layer "F.Fab")
		)
		(fp_line
			(start 0.12065 -0.2794)
			(end 0.12065 -0.3048)
			(stroke
				(width 0.1)
				(type default)
			)
			(layer "F.Fab")
		)
		(fp_line
			(start 0.67945 -0.3048)
			(end 0.67945 0.3048)
			(stroke
				(width 0.1)
				(type default)
			)
			(layer "F.Fab")
		)
		(fp_line
			(start 0.67945 0.3048)
			(end 0.120396 0.3048)
			(stroke
				(width 0.1)
				(type default)
			)
			(layer "F.Fab")
		)
		(pad "1" smd circle
			(at -0.40005 0)
			(size 0 0)
			(layers "F.Cu" "F.Mask" "F.Paste")
			(net "FM_PDB_BUF_EN")
		)
		(pad "2" smd circle
			(at 0.40005 0)
			(size 0 0)
			(layers "F.Cu" "F.Mask" "F.Paste")
			(net "FM_PDB_BUF_EN_R")
		)
	)
	(footprint ""
		(layer "F.Cu")
		(at 133.296914 -402.371052 -90)
		(property "Reference" "C750"
			(at 0 0 270)
			(layer "F.SilkS")
			(hide yes)
			(effects
				(font
					(size 1.27 1.27)
				)
			)
		)
		(property "Value" ""
			(at 0 0 270)
			(layer "F.Fab")
			(effects
				(font
					(size 1.27 1.27)
				)
			)
		)
		(duplicate_pad_numbers_are_jumpers no)
		(fp_line
			(start -0.299974 0.150114)
			(end -0.299974 -0.150114)
			(stroke
				(width 0.1)
				(type default)
			)
			(layer "F.Fab")
		)
		(fp_line
			(start 0.299974 0.150114)
			(end -0.299974 0.150114)
			(stroke
				(width 0.1)
				(type default)
			)
			(layer "F.Fab")
		)
		(fp_line
			(start -0.299974 -0.150114)
			(end 0.299974 -0.150114)
			(stroke
				(width 0.1)
				(type default)
			)
			(layer "F.Fab")
		)
		(fp_line
			(start 0.299974 -0.150114)
			(end 0.299974 0.150114)
			(stroke
				(width 0.1)
				(type default)
			)
			(layer "F.Fab")
		)
		(pad "1" smd rect
			(at -0.2667 0 270)
			(size 0.3048 0.381)
			(layers "F.Cu" "F.Mask" "F.Paste")
			(net "P5E_CPU1_PE2_TX_C_DN<11>")
		)
		(pad "2" smd rect
			(at 0.2667 0 270)
			(size 0.3048 0.381)
			(layers "F.Cu" "F.Mask" "F.Paste")
			(net "P5E_CPU1_PE2_TX_DN<11>")
		)
	)
)
